(kicad_pcb
	(version 20260206)
	(generator "pcbnew")
	(generator_version "10.0")
	(general
		(thickness 1.6)
		(legacy_teardrops no)
	)
	(paper "A4")
	(title_block
		(title "baseboard — 13948-1b.1110WZS1818.brd")
		(comment 1 "Honey Badger (Wiwynn) / footprints 1871-1877 of 2523")
	)
	(layers
		(0 "F.Cu" signal "TOP")
		(4 "In1.Cu" signal "L2GND")
		(6 "In2.Cu" signal "L3")
		(8 "In3.Cu" signal "L4VCC")
		(10 "In4.Cu" signal "L5VCC")
		(12 "In5.Cu" signal "L6")
		(14 "In6.Cu" signal "L7GND")
		(2 "B.Cu" signal "BOTTOM")
		(9 "F.Adhes" user "F.Adhesive")
		(11 "B.Adhes" user "B.Adhesive")
		(13 "F.Paste" user "Package Geometry/Pastemask Top")
		(15 "B.Paste" user "Package Geometry/Pastemask Bottom")
		(5 "F.SilkS" user "Ref Des/Silkscreen Top")
		(7 "B.SilkS" user "Ref Des/Silkscreen Bottom")
		(1 "F.Mask" user "Board Geometry/Soldermask Top")
		(3 "B.Mask" user "Board Geometry/Soldermask Bottom")
		(17 "Dwgs.User" user "User.Drawings")
		(19 "Cmts.User" user "User.Comments")
		(21 "Eco1.User" user "User.Eco1")
		(23 "Eco2.User" user "User.Eco2")
		(25 "Edge.Cuts" user "Board Geometry/Outline")
		(27 "Margin" user)
		(31 "F.CrtYd" user "Package Geometry/Place Bound Top")
		(29 "B.CrtYd" user "Package Geometry/Place Bound Bottom")
		(35 "F.Fab" user "Ref Des/Assembly Top")
		(33 "B.Fab" user "Ref Des/Assembly Bottom")
	)
	(footprint ""
		(layer "B.Cu")
		(at 120.86717 -89.8652 180)
		(property "Reference" "SC1145"
			(at 0 0 0)
			(layer "B.SilkS")
			(hide yes)
			(effects
				(font
					(size 1.27 1.27)
				)
				(justify mirror)
			)
		)
		(property "Value" "SCD1U6D3V1KX-GP"
			(at 2.8321 -1.7399 180)
			(unlocked yes)
			(layer "B.Fab")
			(hide yes)
			(effects
				(font
					(size 1.016 1.016)
					(thickness 0.1524)
				)
				(justify mirror)
			)
		)
		(property "Device Type" "C0201H13"
			(at 2.8321 -3.2639 180)
			(unlocked yes)
			(layer "B.Fab")
			(hide yes)
			(effects
				(font
					(size 1.016 1.016)
					(thickness 0.1524)
				)
				(justify mirror)
			)
		)
		(duplicate_pad_numbers_are_jumpers no)
		(fp_rect
			(start 0.2794 0.6477)
			(end -0.2794 -0.6477)
			(stroke
				(width 0)
				(type default)
			)
			(fill no)
			(layer "B.CrtYd")
		)
		(fp_rect
			(start 0.2794 0.6477)
			(end -0.2794 -0.6477)
			(stroke
				(width 0)
				(type default)
			)
			(fill no)
			(layer "B.Fab")
		)
		(pad "1" smd custom
			(at 0 -0.2794)
			(size 0.0762 0.0762)
			(layers "B.Cu" "B.Mask" "B.Paste")
			(net "GB_VDDH2")
			(options
				(clearance outline)
				(anchor circle)
			)
			(primitives
				(gr_poly
					(pts
						(arc
							(start 0.1524 0.127)
							(mid 0.137521 0.162921)
							(end 0.1016 0.1778)
						)
						(arc
							(start -0.1016 0.1778)
							(mid -0.137521 0.162921)
							(end -0.1524 0.127)
						)
						(arc
							(start -0.1524 -0.127)
							(mid -0.137521 -0.162921)
							(end -0.1016 -0.1778)
						)
						(arc
							(start 0.1016 -0.1778)
							(mid 0.137521 -0.162921)
							(end 0.1524 -0.127)
						)
					)
					(width 0)
					(fill yes)
				)
			)
		)
		(pad "2" smd custom
			(at 0 0.2794)
			(size 0.0762 0.0762)
			(layers "B.Cu" "B.Mask" "B.Paste")
			(net "GND")
			(options
				(clearance outline)
				(anchor circle)
			)
			(primitives
				(gr_poly
					(pts
						(arc
							(start 0.1524 0.127)
							(mid 0.137521 0.162921)
							(end 0.1016 0.1778)
						)
						(arc
							(start -0.1016 0.1778)
							(mid -0.137521 0.162921)
							(end -0.1524 0.127)
						)
						(arc
							(start -0.1524 -0.127)
							(mid -0.137521 -0.162921)
							(end -0.1016 -0.1778)
						)
						(arc
							(start 0.1016 -0.1778)
							(mid 0.137521 -0.162921)
							(end 0.1524 -0.127)
						)
					)
					(width 0)
					(fill yes)
				)
			)
		)
	)
	(footprint ""
		(layer "B.Cu")
		(at 296.799 -174.117 -90)
		(property "Reference" "C215"
			(at 0 0 90)
			(layer "B.SilkS")
			(hide yes)
			(effects
				(font
					(size 1.27 1.27)
				)
				(justify mirror)
			)
		)
		(property "Value" "SC1U10V2KX-1GP"
			(at -1.1811 -2.7051 270)
			(unlocked yes)
			(layer "B.Fab")
			(hide yes)
			(effects
				(font
					(size 1.016 1.016)
					(thickness 0.1524)
				)
				(justify mirror)
			)
		)
		(property "Device Type" "C402H22"
			(at -1.1811 -4.2291 270)
			(unlocked yes)
			(layer "B.Fab")
			(hide yes)
			(effects
				(font
					(size 1.016 1.016)
					(thickness 0.1524)
				)
				(justify mirror)
			)
		)
		(duplicate_pad_numbers_are_jumpers no)
		(fp_rect
			(start 0.4318 0.9525)
			(end -0.4318 -0.9525)
			(stroke
				(width 0)
				(type default)
			)
			(fill no)
			(layer "B.CrtYd")
		)
		(fp_rect
			(start 0.4318 0.9525)
			(end -0.4318 -0.9525)
			(stroke
				(width 0)
				(type default)
			)
			(fill no)
			(layer "B.Fab")
		)
		(pad "1" smd custom
			(at 0 -0.4445 90)
			(size 0.1524 0.1524)
			(layers "B.Cu" "B.Mask" "B.Paste")
			(net "P3V3_STBY")
			(options
				(clearance outline)
				(anchor circle)
			)
			(primitives
				(gr_poly
					(pts
						(arc
							(start 0.3048 0.2032)
							(mid 0.275042 0.275042)
							(end 0.2032 0.3048)
						)
						(arc
							(start -0.2032 0.3048)
							(mid -0.275042 0.275042)
							(end -0.3048 0.2032)
						)
						(arc
							(start -0.3048 -0.2032)
							(mid -0.275042 -0.275042)
							(end -0.2032 -0.3048)
						)
						(arc
							(start 0.2032 -0.3048)
							(mid 0.275042 -0.275042)
							(end 0.3048 -0.2032)
						)
					)
					(width 0)
					(fill yes)
				)
			)
		)
		(pad "2" smd custom
			(at 0 0.4445 90)
			(size 0.1524 0.1524)
			(layers "B.Cu" "B.Mask" "B.Paste")
			(net "GND")
			(options
				(clearance outline)
				(anchor circle)
			)
			(primitives
				(gr_poly
					(pts
						(arc
							(start 0.3048 0.2032)
							(mid 0.275042 0.275042)
							(end 0.2032 0.3048)
						)
						(arc
							(start -0.2032 0.3048)
							(mid -0.275042 0.275042)
							(end -0.3048 0.2032)
						)
						(arc
							(start -0.3048 -0.2032)
							(mid -0.275042 -0.275042)
							(end -0.2032 -0.3048)
						)
						(arc
							(start 0.2032 -0.3048)
							(mid 0.275042 -0.275042)
							(end 0.3048 -0.2032)
						)
					)
					(width 0)
					(fill yes)
				)
			)
		)
	)
	(footprint ""
		(layer "B.Cu")
		(at 102.997 -231.013 -90)
		(property "Reference" "R664"
			(at 0 0 90)
			(layer "B.SilkS")
			(hide yes)
			(effects
				(font
					(size 1.27 1.27)
				)
				(justify mirror)
			)
		)
		(property "Value" "0R2J-2-GP"
			(at -0.064008 -3.993896 270)
			(unlocked yes)
			(layer "B.Fab")
			(hide yes)
			(effects
				(font
					(size 1.016 1.016)
					(thickness 0.1524)
				)
				(justify mirror)
			)
		)
		(property "Device Type" "R402H16"
			(at -0.064008 -5.517896 270)
			(unlocked yes)
			(layer "B.Fab")
			(hide yes)
			(effects
				(font
					(size 1.016 1.016)
					(thickness 0.1524)
				)
				(justify mirror)
			)
		)
		(duplicate_pad_numbers_are_jumpers no)
		(fp_line
			(start -0.508 -0.9398)
			(end 0.508 -0.9398)
			(stroke
				(width 0.1524)
				(type default)
			)
			(layer "B.SilkS")
		)
		(fp_line
			(start 0.508 -0.9398)
			(end 0.508 0.9398)
			(stroke
				(width 0.1524)
				(type default)
			)
			(layer "B.SilkS")
		)
		(fp_rect
			(start 0.508 0.9398)
			(end -0.508 -0.9398)
			(stroke
				(width 0)
				(type default)
			)
			(fill no)
			(layer "B.CrtYd")
		)
		(fp_rect
			(start 0.508 0.9398)
			(end -0.508 -0.9398)
			(stroke
				(width 0)
				(type default)
			)
			(fill no)
			(layer "B.Fab")
		)
		(pad "1" smd custom
			(at 0 -0.4445 90)
			(size 0.1397 0.1397)
			(layers "B.Cu" "B.Mask" "B.Paste")
			(net "SAS_FAULT_LED5")
			(options
				(clearance outline)
				(anchor circle)
			)
			(primitives
				(gr_poly
					(pts
						(arc
							(start -0.1778 0.2794)
							(mid -0.249642 0.249642)
							(end -0.2794 0.1778)
						)
						(arc
							(start -0.2794 -0.1778)
							(mid -0.249642 -0.249642)
							(end -0.1778 -0.2794)
						)
						(arc
							(start 0.1778 -0.2794)
							(mid 0.249642 -0.249642)
							(end 0.2794 -0.1778)
						)
						(arc
							(start 0.2794 0.1778)
							(mid 0.249642 0.249642)
							(end 0.1778 0.2794)
						)
					)
					(width 0)
					(fill yes)
				)
			)
		)
		(pad "2" smd custom
			(at 0 0.4445 90)
			(size 0.1397 0.1397)
			(layers "B.Cu" "B.Mask" "B.Paste")
			(net "SAS_HDD_LED_5")
			(options
				(clearance outline)
				(anchor circle)
			)
			(primitives
				(gr_poly
					(pts
						(arc
							(start -0.1778 0.2794)
							(mid -0.249642 0.249642)
							(end -0.2794 0.1778)
						)
						(arc
							(start -0.2794 -0.1778)
							(mid -0.249642 -0.249642)
							(end -0.1778 -0.2794)
						)
						(arc
							(start 0.1778 -0.2794)
							(mid 0.249642 -0.249642)
							(end 0.2794 -0.1778)
						)
						(arc
							(start 0.2794 0.1778)
							(mid 0.249642 0.249642)
							(end 0.1778 0.2794)
						)
					)
					(width 0)
					(fill yes)
				)
			)
		)
	)
	(footprint ""
		(layer "B.Cu")
		(at 318.008 -176.657 -90)
		(property "Reference" "R315"
			(at 0 0 90)
			(layer "B.SilkS")
			(hide yes)
			(effects
				(font
					(size 1.27 1.27)
				)
				(justify mirror)
			)
		)
		(property "Value" "0R2J-2-GP"
			(at -0.064008 -3.993896 270)
			(unlocked yes)
			(layer "B.Fab")
			(hide yes)
			(effects
				(font
					(size 1.016 1.016)
					(thickness 0.1524)
				)
				(justify mirror)
			)
		)
		(property "Device Type" "R402H16"
			(at -0.064008 -5.517896 270)
			(unlocked yes)
			(layer "B.Fab")
			(hide yes)
			(effects
				(font
					(size 1.016 1.016)
					(thickness 0.1524)
				)
				(justify mirror)
			)
		)
		(duplicate_pad_numbers_are_jumpers no)
		(fp_line
			(start -0.508 -0.9398)
			(end 0.508 -0.9398)
			(stroke
				(width 0.1524)
				(type default)
			)
			(layer "B.SilkS")
		)
		(fp_line
			(start 0.508 -0.9398)
			(end 0.508 0.9398)
			(stroke
				(width 0.1524)
				(type default)
			)
			(layer "B.SilkS")
		)
		(fp_rect
			(start 0.508 0.9398)
			(end -0.508 -0.9398)
			(stroke
				(width 0)
				(type default)
			)
			(fill no)
			(layer "B.CrtYd")
		)
		(fp_rect
			(start 0.508 0.9398)
			(end -0.508 -0.9398)
			(stroke
				(width 0)
				(type default)
			)
			(fill no)
			(layer "B.Fab")
		)
		(pad "1" smd custom
			(at 0 -0.4445 90)
			(size 0.1397 0.1397)
			(layers "B.Cu" "B.Mask" "B.Paste")
			(net "ADC_12V")
			(options
				(clearance outline)
				(anchor circle)
			)
			(primitives
				(gr_poly
					(pts
						(arc
							(start -0.1778 0.2794)
							(mid -0.249642 0.249642)
							(end -0.2794 0.1778)
						)
						(arc
							(start -0.2794 -0.1778)
							(mid -0.249642 -0.249642)
							(end -0.1778 -0.2794)
						)
						(arc
							(start 0.1778 -0.2794)
							(mid 0.249642 -0.249642)
							(end 0.2794 -0.1778)
						)
						(arc
							(start 0.2794 0.1778)
							(mid 0.249642 0.249642)
							(end 0.1778 0.2794)
						)
					)
					(width 0)
					(fill yes)
				)
			)
		)
		(pad "2" smd custom
			(at 0 0.4445 90)
			(size 0.1397 0.1397)
			(layers "B.Cu" "B.Mask" "B.Paste")
			(net "ADC0_12V_BMC")
			(options
				(clearance outline)
				(anchor circle)
			)
			(primitives
				(gr_poly
					(pts
						(arc
							(start -0.1778 0.2794)
							(mid -0.249642 0.249642)
							(end -0.2794 0.1778)
						)
						(arc
							(start -0.2794 -0.1778)
							(mid -0.249642 -0.249642)
							(end -0.1778 -0.2794)
						)
						(arc
							(start 0.1778 -0.2794)
							(mid 0.249642 -0.249642)
							(end 0.2794 -0.1778)
						)
						(arc
							(start 0.2794 0.1778)
							(mid 0.249642 0.249642)
							(end 0.1778 0.2794)
						)
					)
					(width 0)
					(fill yes)
				)
			)
		)
	)
	(footprint ""
		(layer "B.Cu")
		(at 122.69597 -100.33 180)
		(property "Reference" "SC1186"
			(at 0 0 0)
			(layer "B.SilkS")
			(hide yes)
			(effects
				(font
					(size 1.27 1.27)
				)
				(justify mirror)
			)
		)
		(property "Value" "SCD1U6D3V1KX-GP"
			(at 2.8321 -1.7399 180)
			(unlocked yes)
			(layer "B.Fab")
			(hide yes)
			(effects
				(font
					(size 1.016 1.016)
					(thickness 0.1524)
				)
				(justify mirror)
			)
		)
		(property "Device Type" "C0201H13"
			(at 2.8321 -3.2639 180)
			(unlocked yes)
			(layer "B.Fab")
			(hide yes)
			(effects
				(font
					(size 1.016 1.016)
					(thickness 0.1524)
				)
				(justify mirror)
			)
		)
		(duplicate_pad_numbers_are_jumpers no)
		(fp_rect
			(start 0.2794 0.6477)
			(end -0.2794 -0.6477)
			(stroke
				(width 0)
				(type default)
			)
			(fill no)
			(layer "B.CrtYd")
		)
		(fp_rect
			(start 0.2794 0.6477)
			(end -0.2794 -0.6477)
			(stroke
				(width 0)
				(type default)
			)
			(fill no)
			(layer "B.Fab")
		)
		(pad "1" smd custom
			(at 0 -0.2794)
			(size 0.0762 0.0762)
			(layers "B.Cu" "B.Mask" "B.Paste")
			(net "GB_VDDA")
			(options
				(clearance outline)
				(anchor circle)
			)
			(primitives
				(gr_poly
					(pts
						(arc
							(start 0.1524 0.127)
							(mid 0.137521 0.162921)
							(end 0.1016 0.1778)
						)
						(arc
							(start -0.1016 0.1778)
							(mid -0.137521 0.162921)
							(end -0.1524 0.127)
						)
						(arc
							(start -0.1524 -0.127)
							(mid -0.137521 -0.162921)
							(end -0.1016 -0.1778)
						)
						(arc
							(start 0.1016 -0.1778)
							(mid 0.137521 -0.162921)
							(end 0.1524 -0.127)
						)
					)
					(width 0)
					(fill yes)
				)
			)
		)
		(pad "2" smd custom
			(at 0 0.2794)
			(size 0.0762 0.0762)
			(layers "B.Cu" "B.Mask" "B.Paste")
			(net "GND")
			(options
				(clearance outline)
				(anchor circle)
			)
			(primitives
				(gr_poly
					(pts
						(arc
							(start 0.1524 0.127)
							(mid 0.137521 0.162921)
							(end 0.1016 0.1778)
						)
						(arc
							(start -0.1016 0.1778)
							(mid -0.137521 0.162921)
							(end -0.1524 0.127)
						)
						(arc
							(start -0.1524 -0.127)
							(mid -0.137521 -0.162921)
							(end -0.1016 -0.1778)
						)
						(arc
							(start 0.1016 -0.1778)
							(mid 0.137521 -0.162921)
							(end 0.1524 -0.127)
						)
					)
					(width 0)
					(fill yes)
				)
			)
		)
	)
	(footprint ""
		(layer "B.Cu")
		(at 19.170904 -100.400866)
		(property "Reference" "C136"
			(at 0 0 0)
			(layer "B.SilkS")
			(hide yes)
			(effects
				(font
					(size 1.27 1.27)
				)
				(justify mirror)
			)
		)
		(property "Value" "SCD01U50V2KX-1GP"
			(at -1.1811 -2.7051 0)
			(unlocked yes)
			(layer "B.Fab")
			(hide yes)
			(effects
				(font
					(size 1.016 1.016)
					(thickness 0.1524)
				)
				(justify mirror)
			)
		)
		(property "Device Type" "C402H22"
			(at -1.1811 -4.2291 0)
			(unlocked yes)
			(layer "B.Fab")
			(hide yes)
			(effects
				(font
					(size 1.016 1.016)
					(thickness 0.1524)
				)
				(justify mirror)
			)
		)
		(duplicate_pad_numbers_are_jumpers no)
		(fp_rect
			(start 0.4318 0.9525)
			(end -0.4318 -0.9525)
			(stroke
				(width 0)
				(type default)
			)
			(fill no)
			(layer "B.CrtYd")
		)
		(fp_rect
			(start 0.4318 0.9525)
			(end -0.4318 -0.9525)
			(stroke
				(width 0)
				(type default)
			)
			(fill no)
			(layer "B.Fab")
		)
		(pad "1" smd custom
			(at 0 -0.4445 180)
			(size 0.1524 0.1524)
			(layers "B.Cu" "B.Mask" "B.Paste")
			(net "IOC_SAS_RX_N7")
			(options
				(clearance outline)
				(anchor circle)
			)
			(primitives
				(gr_poly
					(pts
						(arc
							(start 0.3048 0.2032)
							(mid 0.275042 0.275042)
							(end 0.2032 0.3048)
						)
						(arc
							(start -0.2032 0.3048)
							(mid -0.275042 0.275042)
							(end -0.3048 0.2032)
						)
						(arc
							(start -0.3048 -0.2032)
							(mid -0.275042 -0.275042)
							(end -0.2032 -0.3048)
						)
						(arc
							(start 0.2032 -0.3048)
							(mid 0.275042 -0.275042)
							(end 0.3048 -0.2032)
						)
					)
					(width 0)
					(fill yes)
				)
			)
		)
		(pad "2" smd custom
			(at 0 0.4445 180)
			(size 0.1524 0.1524)
			(layers "B.Cu" "B.Mask" "B.Paste")
			(net "SAS_EXT_CONN_RX19_N")
			(options
				(clearance outline)
				(anchor circle)
			)
			(primitives
				(gr_poly
					(pts
						(arc
							(start 0.3048 0.2032)
							(mid 0.275042 0.275042)
							(end 0.2032 0.3048)
						)
						(arc
							(start -0.2032 0.3048)
							(mid -0.275042 0.275042)
							(end -0.3048 0.2032)
						)
						(arc
							(start -0.3048 -0.2032)
							(mid -0.275042 -0.275042)
							(end -0.2032 -0.3048)
						)
						(arc
							(start 0.2032 -0.3048)
							(mid 0.275042 -0.275042)
							(end 0.3048 -0.2032)
						)
					)
					(width 0)
					(fill yes)
				)
			)
		)
	)
	(footprint ""
		(layer "B.Cu")
		(at 104.325166 -50.292 180)
		(property "Reference" "SC1037"
			(at 0 0 0)
			(layer "B.SilkS")
			(hide yes)
			(effects
				(font
					(size 1.27 1.27)
				)
				(justify mirror)
			)
		)
		(property "Value" "SCD1U16V2KX-3GP"
			(at -1.1811 -2.7051 180)
			(unlocked yes)
			(layer "B.Fab")
			(hide yes)
			(effects
				(font
					(size 1.016 1.016)
					(thickness 0.1524)
				)
				(justify mirror)
			)
		)
		(property "Device Type" "C402H22"
			(at -1.1811 -4.2291 180)
			(unlocked yes)
			(layer "B.Fab")
			(hide yes)
			(effects
				(font
					(size 1.016 1.016)
					(thickness 0.1524)
				)
				(justify mirror)
			)
		)
		(duplicate_pad_numbers_are_jumpers no)
		(fp_rect
			(start 0.4318 0.9525)
			(end -0.4318 -0.9525)
			(stroke
				(width 0)
				(type default)
			)
			(fill no)
			(layer "B.CrtYd")
		)
		(fp_rect
			(start 0.4318 0.9525)
			(end -0.4318 -0.9525)
			(stroke
				(width 0)
				(type default)
			)
			(fill no)
			(layer "B.Fab")
		)
		(pad "1" smd custom
			(at 0 -0.4445)
			(size 0.1524 0.1524)
			(layers "B.Cu" "B.Mask" "B.Paste")
			(net "P0V955_C")
			(options
				(clearance outline)
				(anchor circle)
			)
			(primitives
				(gr_poly
					(pts
						(arc
							(start 0.3048 0.2032)
							(mid 0.275042 0.275042)
							(end 0.2032 0.3048)
						)
						(arc
							(start -0.2032 0.3048)
							(mid -0.275042 0.275042)
							(end -0.3048 0.2032)
						)
						(arc
							(start -0.3048 -0.2032)
							(mid -0.275042 -0.275042)
							(end -0.2032 -0.3048)
						)
						(arc
							(start 0.2032 -0.3048)
							(mid 0.275042 -0.275042)
							(end 0.3048 -0.2032)
						)
					)
					(width 0)
					(fill yes)
				)
			)
		)
		(pad "2" smd custom
			(at 0 0.4445)
			(size 0.1524 0.1524)
			(layers "B.Cu" "B.Mask" "B.Paste")
			(net "GND")
			(options
				(clearance outline)
				(anchor circle)
			)
			(primitives
				(gr_poly
					(pts
						(arc
							(start 0.3048 0.2032)
							(mid 0.275042 0.275042)
							(end 0.2032 0.3048)
						)
						(arc
							(start -0.2032 0.3048)
							(mid -0.275042 0.275042)
							(end -0.3048 0.2032)
						)
						(arc
							(start -0.3048 -0.2032)
							(mid -0.275042 -0.275042)
							(end -0.2032 -0.3048)
						)
						(arc
							(start 0.2032 -0.3048)
							(mid 0.275042 -0.275042)
							(end 0.3048 -0.2032)
						)
					)
					(width 0)
					(fill yes)
				)
			)
		)
	)
)
